# S9S_MB_2U (Grand Teton) — schematic netlist excerpt (pin names and nets, part order shuffled) for the footprints in the layout excerpt that follows; sources: Cadence DE-HDL packaged netlist, KiCad conversion of 03242023_DA0F0TMBIJ0_F0T_Motherboard_J_brd_V01_OCP.brd

R2408  Q_RES  0 5% CHIP  pkg 0402LF  page 281 : A = PWRGD_PVPP_HBM_CPU0_R ; B = PWRGD_PVPP_HBM_CPU0
R1350  Q_RES  100K 1% CHIP  pkg 0402LF  page 154 : A = RMII_OCP_BMC_CRSDV ; B = GND

(kicad_pcb
	(version 20260206)
	(generator "pcbnew")
	(generator_version "10.0")
	(general
		(thickness 1.6)
		(legacy_teardrops no)
	)
	(paper "A4")
	(title_block
		(title "03242023_DA0F0TMBIJ0_F0T_Motherboard_J_brd_V01_OCP.brd")
		(comment 1 "Grand Teton / footprints 2026-2027 of 6105")
	)
	(layers
		(0 "F.Cu" signal "TOP")
		(4 "In1.Cu" signal "GND")
		(6 "In2.Cu" signal "IN1")
		(8 "In3.Cu" signal "GND1")
		(10 "In4.Cu" signal "IN2")
		(12 "In5.Cu" signal "GND2")
		(14 "In6.Cu" signal "IN3")
		(16 "In7.Cu" signal "GND3")
		(18 "In8.Cu" signal "VCC")
		(20 "In9.Cu" signal "VCC1")
		(22 "In10.Cu" signal "GND4")
		(24 "In11.Cu" signal "IN4")
		(26 "In12.Cu" signal "GND5")
		(28 "In13.Cu" signal "IN5")
		(30 "In14.Cu" signal "GND6")
		(32 "In15.Cu" signal "IN6")
		(34 "In16.Cu" signal "GND7")
		(2 "B.Cu" signal "BOTTOM")
		(9 "F.Adhes" user "F.Adhesive")
		(11 "B.Adhes" user "B.Adhesive")
		(13 "F.Paste" user "Package Geometry/Pastemask Top")
		(15 "B.Paste" user "Package Geometry/Pastemask Bottom")
		(5 "F.SilkS" user "Ref Des/Silkscreen Top")
		(7 "B.SilkS" user "Ref Des/Silkscreen Bottom")
		(1 "F.Mask" user "Board Geometry/Soldermask Top")
		(3 "B.Mask" user "Board Geometry/Soldermask Bottom")
		(17 "Dwgs.User" user "User.Drawings")
		(19 "Cmts.User" user "User.Comments")
		(21 "Eco1.User" user "User.Eco1")
		(23 "Eco2.User" user "User.Eco2")
		(25 "Edge.Cuts" user "Board Geometry/Outline")
		(27 "Margin" user)
		(31 "F.CrtYd" user "Package Geometry/Place Bound Top")
		(29 "B.CrtYd" user "Package Geometry/Place Bound Bottom")
		(35 "F.Fab" user "Ref Des/Assembly Top")
		(33 "B.Fab" user "Ref Des/Assembly Bottom")
	)
	(footprint ""
		(layer "F.Cu")
		(at 197.876668 -76.016866)
		(property "Reference" "R1350"
			(at 0 0 0)
			(layer "F.SilkS")
			(hide yes)
			(effects
				(font
					(size 1.27 1.27)
				)
			)
		)
		(property "Value" ""
			(at 0 0 0)
			(layer "F.Fab")
			(effects
				(font
					(size 1.27 1.27)
				)
			)
		)
		(duplicate_pad_numbers_are_jumpers no)
		(fp_line
			(start -0.7874 -0.4064)
			(end 0.7874 -0.4064)
			(stroke
				(width 0.1524)
				(type default)
			)
			(layer "F.SilkS")
		)
		(fp_line
			(start -0.7874 0.4064)
			(end -0.7874 -0.4064)
			(stroke
				(width 0.1524)
				(type default)
			)
			(layer "F.SilkS")
		)
		(fp_line
			(start 0.7874 -0.4064)
			(end 0.7874 0.4064)
			(stroke
				(width 0.1524)
				(type default)
			)
			(layer "F.SilkS")
		)
		(fp_line
			(start 0.7874 0.4064)
			(end -0.7874 0.4064)
			(stroke
				(width 0.1524)
				(type default)
			)
			(layer "F.SilkS")
		)
		(fp_line
			(start -0.67945 -0.305054)
			(end -0.12065 -0.305054)
			(stroke
				(width 0.1)
				(type default)
			)
			(layer "F.Fab")
		)
		(fp_line
			(start -0.67945 0.3048)
			(end -0.67945 -0.305054)
			(stroke
				(width 0.1)
				(type default)
			)
			(layer "F.Fab")
		)
		(fp_line
			(start -0.12065 -0.305054)
			(end -0.12065 -0.2794)
			(stroke
				(width 0.1)
				(type default)
			)
			(layer "F.Fab")
		)
		(fp_line
			(start -0.12065 -0.2794)
			(end 0.12065 -0.2794)
			(stroke
				(width 0.1)
				(type default)
			)
			(layer "F.Fab")
		)
		(fp_line
			(start -0.12065 0.2794)
			(end -0.12065 0.3048)
			(stroke
				(width 0.1)
				(type default)
			)
			(layer "F.Fab")
		)
		(fp_line
			(start -0.12065 0.3048)
			(end -0.67945 0.3048)
			(stroke
				(width 0.1)
				(type default)
			)
			(layer "F.Fab")
		)
		(fp_line
			(start 0.120396 0.2794)
			(end -0.12065 0.2794)
			(stroke
				(width 0.1)
				(type default)
			)
			(layer "F.Fab")
		)
		(fp_line
			(start 0.120396 0.3048)
			(end 0.120396 0.2794)
			(stroke
				(width 0.1)
				(type default)
			)
			(layer "F.Fab")
		)
		(fp_line
			(start 0.12065 -0.3048)
			(end 0.67945 -0.3048)
			(stroke
				(width 0.1)
				(type default)
			)
			(layer "F.Fab")
		)
		(fp_line
			(start 0.12065 -0.2794)
			(end 0.12065 -0.3048)
			(stroke
				(width 0.1)
				(type default)
			)
			(layer "F.Fab")
		)
		(fp_line
			(start 0.67945 -0.3048)
			(end 0.67945 0.3048)
			(stroke
				(width 0.1)
				(type default)
			)
			(layer "F.Fab")
		)
		(fp_line
			(start 0.67945 0.3048)
			(end 0.120396 0.3048)
			(stroke
				(width 0.1)
				(type default)
			)
			(layer "F.Fab")
		)
		(pad "1" smd circle
			(at -0.40005 0)
			(size 0 0)
			(layers "F.Cu" "F.Mask" "F.Paste")
			(net "RMII_OCP_BMC_CRSDV")
		)
		(pad "2" smd circle
			(at 0.40005 0)
			(size 0 0)
			(layers "F.Cu" "F.Mask" "F.Paste")
			(net "GND")
		)
	)
	(footprint ""
		(layer "F.Cu")
		(at 366.637824 -354.652326 180)
		(property "Reference" "R2408"
			(at 0 0 180)
			(layer "F.SilkS")
			(hide yes)
			(effects
				(font
					(size 1.27 1.27)
				)
			)
		)
		(property "Value" ""
			(at 0 0 180)
			(layer "F.Fab")
			(effects
				(font
					(size 1.27 1.27)
				)
			)
		)
		(duplicate_pad_numbers_are_jumpers no)
		(fp_line
			(start 0.7874 0.4064)
			(end -0.7874 0.4064)
			(stroke
				(width 0.1524)
				(type default)
			)
			(layer "F.SilkS")
		)
		(fp_line
			(start 0.7874 -0.4064)
			(end 0.7874 0.4064)
			(stroke
				(width 0.1524)
				(type default)
			)
			(layer "F.SilkS")
		)
		(fp_line
			(start -0.7874 0.4064)
			(end -0.7874 -0.4064)
			(stroke
				(width 0.1524)
				(type default)
			)
			(layer "F.SilkS")
		)
		(fp_line
			(start -0.7874 -0.4064)
			(end 0.7874 -0.4064)
			(stroke
				(width 0.1524)
				(type default)
			)
			(layer "F.SilkS")
		)
		(fp_line
			(start 0.67945 0.3048)
			(end 0.120396 0.3048)
			(stroke
				(width 0.1)
				(type default)
			)
			(layer "F.Fab")
		)
		(fp_line
			(start 0.67945 -0.3048)
			(end 0.67945 0.3048)
			(stroke
				(width 0.1)
				(type default)
			)
			(layer "F.Fab")
		)
		(fp_line
			(start 0.12065 -0.2794)
			(end 0.12065 -0.3048)
			(stroke
				(width 0.1)
				(type default)
			)
			(layer "F.Fab")
		)
		(fp_line
			(start 0.12065 -0.3048)
			(end 0.67945 -0.3048)
			(stroke
				(width 0.1)
				(type default)
			)
			(layer "F.Fab")
		)
		(fp_line
			(start 0.120396 0.3048)
			(end 0.120396 0.2794)
			(stroke
				(width 0.1)
				(type default)
			)
			(layer "F.Fab")
		)
		(fp_line
			(start 0.120396 0.2794)
			(end -0.12065 0.2794)
			(stroke
				(width 0.1)
				(type default)
			)
			(layer "F.Fab")
		)
		(fp_line
			(start -0.12065 0.3048)
			(end -0.67945 0.3048)
			(stroke
				(width 0.1)
				(type default)
			)
			(layer "F.Fab")
		)
		(fp_line
			(start -0.12065 0.2794)
			(end -0.12065 0.3048)
			(stroke
				(width 0.1)
				(type default)
			)
			(layer "F.Fab")
		)
		(fp_line
			(start -0.12065 -0.2794)
			(end 0.12065 -0.2794)
			(stroke
				(width 0.1)
				(type default)
			)
			(layer "F.Fab")
		)
		(fp_line
			(start -0.12065 -0.305054)
			(end -0.12065 -0.2794)
			(stroke
				(width 0.1)
				(type default)
			)
			(layer "F.Fab")
		)
		(fp_line
			(start -0.67945 0.3048)
			(end -0.67945 -0.305054)
			(stroke
				(width 0.1)
				(type default)
			)
			(layer "F.Fab")
		)
		(fp_line
			(start -0.67945 -0.305054)
			(end -0.12065 -0.305054)
			(stroke
				(width 0.1)
				(type default)
			)
			(layer "F.Fab")
		)
		(pad "1" smd circle
			(at -0.40005 0 180)
			(size 0 0)
			(layers "F.Cu" "F.Mask" "F.Paste")
			(net "PWRGD_PVPP_HBM_CPU0_R")
		)
		(pad "2" smd circle
			(at 0.40005 0 180)
			(size 0 0)
			(layers "F.Cu" "F.Mask" "F.Paste")
			(net "PWRGD_PVPP_HBM_CPU0")
		)
	)
)
